# S9S_MB_2U (Grand Teton) — schematic netlist excerpt (pin names and nets, part order shuffled) for the footprints in the layout excerpt that follows; sources: Cadence DE-HDL packaged netlist, KiCad conversion of 03242023_DA0F0TMBIJ0_F0T_Motherboard_J_brd_V01_OCP.brd

R3145  Q_RES  10K 1% CHIP  pkg 0402LF  page 162 : A = P3V3_AUX ; B = HP_LVC3_OCP_V3_2_ATTN_OUT_SW_N
C683  Q_CAP_DIFFBUS  DIFF BUS_0.22UF 6.3V 20% X6S  pkg C0201  page 177 : \1\ = P5E_CPU1_PE4_TX_C_DP<13> ; \2\ = P5E_CPU1_PE4_TX_DP<13>
C420  Q_CAP  22UF 4V 20% X6S  pkg C0402  page 74 : A = PVCCFA_EHV_CPU0 ; B = GND

(kicad_pcb
	(version 20260206)
	(generator "pcbnew")
	(generator_version "10.0")
	(general
		(thickness 1.6)
		(legacy_teardrops no)
	)
	(paper "A4")
	(title_block
		(title "03242023_DA0F0TMBIJ0_F0T_Motherboard_J_brd_V01_OCP.brd")
		(comment 1 "Grand Teton / footprints 4112-4114 of 6105")
	)
	(layers
		(0 "F.Cu" signal "TOP")
		(4 "In1.Cu" signal "GND")
		(6 "In2.Cu" signal "IN1")
		(8 "In3.Cu" signal "GND1")
		(10 "In4.Cu" signal "IN2")
		(12 "In5.Cu" signal "GND2")
		(14 "In6.Cu" signal "IN3")
		(16 "In7.Cu" signal "GND3")
		(18 "In8.Cu" signal "VCC")
		(20 "In9.Cu" signal "VCC1")
		(22 "In10.Cu" signal "GND4")
		(24 "In11.Cu" signal "IN4")
		(26 "In12.Cu" signal "GND5")
		(28 "In13.Cu" signal "IN5")
		(30 "In14.Cu" signal "GND6")
		(32 "In15.Cu" signal "IN6")
		(34 "In16.Cu" signal "GND7")
		(2 "B.Cu" signal "BOTTOM")
		(9 "F.Adhes" user "F.Adhesive")
		(11 "B.Adhes" user "B.Adhesive")
		(13 "F.Paste" user "Package Geometry/Pastemask Top")
		(15 "B.Paste" user "Package Geometry/Pastemask Bottom")
		(5 "F.SilkS" user "Ref Des/Silkscreen Top")
		(7 "B.SilkS" user "Ref Des/Silkscreen Bottom")
		(1 "F.Mask" user "Board Geometry/Soldermask Top")
		(3 "B.Mask" user "Board Geometry/Soldermask Bottom")
		(17 "Dwgs.User" user "User.Drawings")
		(19 "Cmts.User" user "User.Comments")
		(21 "Eco1.User" user "User.Eco1")
		(23 "Eco2.User" user "User.Eco2")
		(25 "Edge.Cuts" user "Board Geometry/Outline")
		(27 "Margin" user)
		(31 "F.CrtYd" user "Package Geometry/Place Bound Top")
		(29 "B.CrtYd" user "Package Geometry/Place Bound Bottom")
		(35 "F.Fab" user "Ref Des/Assembly Top")
		(33 "B.Fab" user "Ref Des/Assembly Bottom")
	)
	(footprint ""
		(layer "F.Cu")
		(at 31.856426 -77.783944 180)
		(property "Reference" "R3145"
			(at 0 0 180)
			(layer "F.SilkS")
			(hide yes)
			(effects
				(font
					(size 1.27 1.27)
				)
			)
		)
		(property "Value" ""
			(at 0 0 180)
			(layer "F.Fab")
			(effects
				(font
					(size 1.27 1.27)
				)
			)
		)
		(duplicate_pad_numbers_are_jumpers no)
		(fp_line
			(start 0.7874 0.4064)
			(end -0.7874 0.4064)
			(stroke
				(width 0.1524)
				(type default)
			)
			(layer "F.SilkS")
		)
		(fp_line
			(start 0.7874 -0.4064)
			(end 0.7874 0.4064)
			(stroke
				(width 0.1524)
				(type default)
			)
			(layer "F.SilkS")
		)
		(fp_line
			(start -0.7874 0.4064)
			(end -0.7874 -0.4064)
			(stroke
				(width 0.1524)
				(type default)
			)
			(layer "F.SilkS")
		)
		(fp_line
			(start -0.7874 -0.4064)
			(end 0.7874 -0.4064)
			(stroke
				(width 0.1524)
				(type default)
			)
			(layer "F.SilkS")
		)
		(fp_line
			(start 0.67945 0.3048)
			(end 0.120396 0.3048)
			(stroke
				(width 0.1)
				(type default)
			)
			(layer "F.Fab")
		)
		(fp_line
			(start 0.67945 -0.3048)
			(end 0.67945 0.3048)
			(stroke
				(width 0.1)
				(type default)
			)
			(layer "F.Fab")
		)
		(fp_line
			(start 0.12065 -0.2794)
			(end 0.12065 -0.3048)
			(stroke
				(width 0.1)
				(type default)
			)
			(layer "F.Fab")
		)
		(fp_line
			(start 0.12065 -0.3048)
			(end 0.67945 -0.3048)
			(stroke
				(width 0.1)
				(type default)
			)
			(layer "F.Fab")
		)
		(fp_line
			(start 0.120396 0.3048)
			(end 0.120396 0.2794)
			(stroke
				(width 0.1)
				(type default)
			)
			(layer "F.Fab")
		)
		(fp_line
			(start 0.120396 0.2794)
			(end -0.12065 0.2794)
			(stroke
				(width 0.1)
				(type default)
			)
			(layer "F.Fab")
		)
		(fp_line
			(start -0.12065 0.3048)
			(end -0.67945 0.3048)
			(stroke
				(width 0.1)
				(type default)
			)
			(layer "F.Fab")
		)
		(fp_line
			(start -0.12065 0.2794)
			(end -0.12065 0.3048)
			(stroke
				(width 0.1)
				(type default)
			)
			(layer "F.Fab")
		)
		(fp_line
			(start -0.12065 -0.2794)
			(end 0.12065 -0.2794)
			(stroke
				(width 0.1)
				(type default)
			)
			(layer "F.Fab")
		)
		(fp_line
			(start -0.12065 -0.305054)
			(end -0.12065 -0.2794)
			(stroke
				(width 0.1)
				(type default)
			)
			(layer "F.Fab")
		)
		(fp_line
			(start -0.67945 0.3048)
			(end -0.67945 -0.305054)
			(stroke
				(width 0.1)
				(type default)
			)
			(layer "F.Fab")
		)
		(fp_line
			(start -0.67945 -0.305054)
			(end -0.12065 -0.305054)
			(stroke
				(width 0.1)
				(type default)
			)
			(layer "F.Fab")
		)
		(pad "1" smd circle
			(at -0.40005 0 180)
			(size 0 0)
			(layers "F.Cu" "F.Mask" "F.Paste")
			(net "P3V3_AUX")
		)
		(pad "2" smd circle
			(at 0.40005 0 180)
			(size 0 0)
			(layers "F.Cu" "F.Mask" "F.Paste")
			(net "HP_LVC3_OCP_V3_2_ATTN_OUT_SW_N")
		)
	)
	(footprint ""
		(layer "F.Cu")
		(at 352.264726 -258.726686 90)
		(property "Reference" "C420"
			(at 0 0 90)
			(layer "F.SilkS")
			(hide yes)
			(effects
				(font
					(size 1.27 1.27)
				)
			)
		)
		(property "Value" ""
			(at 0 0 90)
			(layer "F.Fab")
			(effects
				(font
					(size 1.27 1.27)
				)
			)
		)
		(duplicate_pad_numbers_are_jumpers no)
		(fp_line
			(start 0.7874 -0.4064)
			(end 0.7874 0.4064)
			(stroke
				(width 0.1524)
				(type default)
			)
			(layer "F.SilkS")
		)
		(fp_line
			(start -0.7874 -0.4064)
			(end 0.7874 -0.4064)
			(stroke
				(width 0.1524)
				(type default)
			)
			(layer "F.SilkS")
		)
		(fp_line
			(start 0.7874 0.4064)
			(end -0.7874 0.4064)
			(stroke
				(width 0.1524)
				(type default)
			)
			(layer "F.SilkS")
		)
		(fp_line
			(start -0.7874 0.4064)
			(end -0.7874 -0.4064)
			(stroke
				(width 0.1524)
				(type default)
			)
			(layer "F.SilkS")
		)
		(fp_line
			(start -0.12065 -0.305054)
			(end -0.12065 -0.2794)
			(stroke
				(width 0.1)
				(type default)
			)
			(layer "F.Fab")
		)
		(fp_line
			(start -0.67945 -0.305054)
			(end -0.12065 -0.305054)
			(stroke
				(width 0.1)
				(type default)
			)
			(layer "F.Fab")
		)
		(fp_line
			(start 0.67945 -0.3048)
			(end 0.67945 0.3048)
			(stroke
				(width 0.1)
				(type default)
			)
			(layer "F.Fab")
		)
		(fp_line
			(start 0.12065 -0.3048)
			(end 0.67945 -0.3048)
			(stroke
				(width 0.1)
				(type default)
			)
			(layer "F.Fab")
		)
		(fp_line
			(start 0.12065 -0.2794)
			(end 0.12065 -0.3048)
			(stroke
				(width 0.1)
				(type default)
			)
			(layer "F.Fab")
		)
		(fp_line
			(start -0.12065 -0.2794)
			(end 0.12065 -0.2794)
			(stroke
				(width 0.1)
				(type default)
			)
			(layer "F.Fab")
		)
		(fp_line
			(start 0.120396 0.2794)
			(end -0.12065 0.2794)
			(stroke
				(width 0.1)
				(type default)
			)
			(layer "F.Fab")
		)
		(fp_line
			(start -0.12065 0.2794)
			(end -0.12065 0.3048)
			(stroke
				(width 0.1)
				(type default)
			)
			(layer "F.Fab")
		)
		(fp_line
			(start 0.67945 0.3048)
			(end 0.120396 0.3048)
			(stroke
				(width 0.1)
				(type default)
			)
			(layer "F.Fab")
		)
		(fp_line
			(start 0.120396 0.3048)
			(end 0.120396 0.2794)
			(stroke
				(width 0.1)
				(type default)
			)
			(layer "F.Fab")
		)
		(fp_line
			(start -0.12065 0.3048)
			(end -0.67945 0.3048)
			(stroke
				(width 0.1)
				(type default)
			)
			(layer "F.Fab")
		)
		(fp_line
			(start -0.67945 0.3048)
			(end -0.67945 -0.305054)
			(stroke
				(width 0.1)
				(type default)
			)
			(layer "F.Fab")
		)
		(pad "1" smd circle
			(at -0.40005 0 90)
			(size 0 0)
			(layers "F.Cu" "F.Mask" "F.Paste")
			(net "PVCCFA_EHV_CPU0")
		)
		(pad "2" smd circle
			(at 0.40005 0 90)
			(size 0 0)
			(layers "F.Cu" "F.Mask" "F.Paste")
			(net "GND")
		)
	)
	(footprint ""
		(layer "F.Cu")
		(at 90.037158 -408.517344 -90)
		(property "Reference" "C683"
			(at 0 0 270)
			(layer "F.SilkS")
			(hide yes)
			(effects
				(font
					(size 1.27 1.27)
				)
			)
		)
		(property "Value" ""
			(at 0 0 270)
			(layer "F.Fab")
			(effects
				(font
					(size 1.27 1.27)
				)
			)
		)
		(duplicate_pad_numbers_are_jumpers no)
		(fp_line
			(start -0.299974 0.150114)
			(end -0.299974 -0.150114)
			(stroke
				(width 0.1)
				(type default)
			)
			(layer "F.Fab")
		)
		(fp_line
			(start 0.299974 0.150114)
			(end -0.299974 0.150114)
			(stroke
				(width 0.1)
				(type default)
			)
			(layer "F.Fab")
		)
		(fp_line
			(start -0.299974 -0.150114)
			(end 0.299974 -0.150114)
			(stroke
				(width 0.1)
				(type default)
			)
			(layer "F.Fab")
		)
		(fp_line
			(start 0.299974 -0.150114)
			(end 0.299974 0.150114)
			(stroke
				(width 0.1)
				(type default)
			)
			(layer "F.Fab")
		)
		(pad "1" smd rect
			(at -0.2667 0 270)
			(size 0.3048 0.381)
			(layers "F.Cu" "F.Mask" "F.Paste")
			(net "P5E_CPU1_PE4_TX_C_DP<13>")
		)
		(pad "2" smd rect
			(at 0.2667 0 270)
			(size 0.3048 0.381)
			(layers "F.Cu" "F.Mask" "F.Paste")
			(net "P5E_CPU1_PE4_TX_DP<13>")
		)
	)
)
